# S9S_MB_2U (Grand Teton) — schematic netlist excerpt (pin names and nets, part order shuffled) for the footprints in the layout excerpt that follows; sources: Cadence DE-HDL packaged netlist, KiCad conversion of 03242023_DA0F0TMBIJ0_F0T_Motherboard_J_brd_V01_OCP.brd

C1877  Q_CAP  0.1UF 25V 10% X7R  pkg 0402  page 165 : A = P3V3_AUX ; B = GND
R3703  Q_RES  10K 1% EMPTY  pkg 0402LF  page 233 : A = P3V3_AUX ; B = PCA9548_PCIE0_ADDR2

(kicad_pcb
	(version 20260206)
	(generator "pcbnew")
	(generator_version "10.0")
	(general
		(thickness 1.6)
		(legacy_teardrops no)
	)
	(paper "A4")
	(title_block
		(title "03242023_DA0F0TMBIJ0_F0T_Motherboard_J_brd_V01_OCP.brd")
		(comment 1 "Grand Teton / footprints 1449-1451 of 6105")
	)
	(layers
		(0 "F.Cu" signal "TOP")
		(4 "In1.Cu" signal "GND")
		(6 "In2.Cu" signal "IN1")
		(8 "In3.Cu" signal "GND1")
		(10 "In4.Cu" signal "IN2")
		(12 "In5.Cu" signal "GND2")
		(14 "In6.Cu" signal "IN3")
		(16 "In7.Cu" signal "GND3")
		(18 "In8.Cu" signal "VCC")
		(20 "In9.Cu" signal "VCC1")
		(22 "In10.Cu" signal "GND4")
		(24 "In11.Cu" signal "IN4")
		(26 "In12.Cu" signal "GND5")
		(28 "In13.Cu" signal "IN5")
		(30 "In14.Cu" signal "GND6")
		(32 "In15.Cu" signal "IN6")
		(34 "In16.Cu" signal "GND7")
		(2 "B.Cu" signal "BOTTOM")
		(9 "F.Adhes" user "F.Adhesive")
		(11 "B.Adhes" user "B.Adhesive")
		(13 "F.Paste" user "Package Geometry/Pastemask Top")
		(15 "B.Paste" user "Package Geometry/Pastemask Bottom")
		(5 "F.SilkS" user "Ref Des/Silkscreen Top")
		(7 "B.SilkS" user "Ref Des/Silkscreen Bottom")
		(1 "F.Mask" user "Board Geometry/Soldermask Top")
		(3 "B.Mask" user "Board Geometry/Soldermask Bottom")
		(17 "Dwgs.User" user "User.Drawings")
		(19 "Cmts.User" user "User.Comments")
		(21 "Eco1.User" user "User.Eco1")
		(23 "Eco2.User" user "User.Eco2")
		(25 "Edge.Cuts" user "Board Geometry/Outline")
		(27 "Margin" user)
		(31 "F.CrtYd" user "Package Geometry/Place Bound Top")
		(29 "B.CrtYd" user "Package Geometry/Place Bound Bottom")
		(35 "F.Fab" user "Ref Des/Assembly Top")
		(33 "B.Fab" user "Ref Des/Assembly Bottom")
	)
	(footprint ""
		(layer "F.Cu")
		(at 145.17116 -40.114728 180)
		(property "Reference" "C1877"
			(at 0 0 180)
			(layer "F.SilkS")
			(hide yes)
			(effects
				(font
					(size 1.27 1.27)
				)
			)
		)
		(property "Value" ""
			(at 0 0 180)
			(layer "F.Fab")
			(effects
				(font
					(size 1.27 1.27)
				)
			)
		)
		(duplicate_pad_numbers_are_jumpers no)
		(fp_line
			(start 0.7874 0.4064)
			(end -0.7874 0.4064)
			(stroke
				(width 0.1524)
				(type default)
			)
			(layer "F.SilkS")
		)
		(fp_line
			(start 0.7874 -0.4064)
			(end 0.7874 0.4064)
			(stroke
				(width 0.1524)
				(type default)
			)
			(layer "F.SilkS")
		)
		(fp_line
			(start -0.7874 0.4064)
			(end -0.7874 -0.4064)
			(stroke
				(width 0.1524)
				(type default)
			)
			(layer "F.SilkS")
		)
		(fp_line
			(start -0.7874 -0.4064)
			(end 0.7874 -0.4064)
			(stroke
				(width 0.1524)
				(type default)
			)
			(layer "F.SilkS")
		)
		(fp_line
			(start 0.67945 0.3048)
			(end 0.120396 0.3048)
			(stroke
				(width 0.1)
				(type default)
			)
			(layer "F.Fab")
		)
		(fp_line
			(start 0.67945 -0.3048)
			(end 0.67945 0.3048)
			(stroke
				(width 0.1)
				(type default)
			)
			(layer "F.Fab")
		)
		(fp_line
			(start 0.12065 -0.2794)
			(end 0.12065 -0.3048)
			(stroke
				(width 0.1)
				(type default)
			)
			(layer "F.Fab")
		)
		(fp_line
			(start 0.12065 -0.3048)
			(end 0.67945 -0.3048)
			(stroke
				(width 0.1)
				(type default)
			)
			(layer "F.Fab")
		)
		(fp_line
			(start 0.120396 0.3048)
			(end 0.120396 0.2794)
			(stroke
				(width 0.1)
				(type default)
			)
			(layer "F.Fab")
		)
		(fp_line
			(start 0.120396 0.2794)
			(end -0.12065 0.2794)
			(stroke
				(width 0.1)
				(type default)
			)
			(layer "F.Fab")
		)
		(fp_line
			(start -0.12065 0.3048)
			(end -0.67945 0.3048)
			(stroke
				(width 0.1)
				(type default)
			)
			(layer "F.Fab")
		)
		(fp_line
			(start -0.12065 0.2794)
			(end -0.12065 0.3048)
			(stroke
				(width 0.1)
				(type default)
			)
			(layer "F.Fab")
		)
		(fp_line
			(start -0.12065 -0.2794)
			(end 0.12065 -0.2794)
			(stroke
				(width 0.1)
				(type default)
			)
			(layer "F.Fab")
		)
		(fp_line
			(start -0.12065 -0.305054)
			(end -0.12065 -0.2794)
			(stroke
				(width 0.1)
				(type default)
			)
			(layer "F.Fab")
		)
		(fp_line
			(start -0.67945 0.3048)
			(end -0.67945 -0.305054)
			(stroke
				(width 0.1)
				(type default)
			)
			(layer "F.Fab")
		)
		(fp_line
			(start -0.67945 -0.305054)
			(end -0.12065 -0.305054)
			(stroke
				(width 0.1)
				(type default)
			)
			(layer "F.Fab")
		)
		(pad "1" smd circle
			(at -0.40005 0 180)
			(size 0 0)
			(layers "F.Cu" "F.Mask" "F.Paste")
			(net "P3V3_AUX")
		)
		(pad "2" smd circle
			(at 0.40005 0 180)
			(size 0 0)
			(layers "F.Cu" "F.Mask" "F.Paste")
			(net "GND")
		)
	)
	(footprint ""
		(layer "F.Cu")
		(at 68.093336 -111.65967 180)
		(property "Reference" "R3703"
			(at 0 0 180)
			(layer "F.SilkS")
			(hide yes)
			(effects
				(font
					(size 1.27 1.27)
				)
			)
		)
		(property "Value" ""
			(at 0 0 180)
			(layer "F.Fab")
			(effects
				(font
					(size 1.27 1.27)
				)
			)
		)
		(duplicate_pad_numbers_are_jumpers no)
		(fp_line
			(start 0.7874 0.4064)
			(end -0.7874 0.4064)
			(stroke
				(width 0.1524)
				(type default)
			)
			(layer "F.SilkS")
		)
		(fp_line
			(start 0.7874 -0.4064)
			(end 0.7874 0.4064)
			(stroke
				(width 0.1524)
				(type default)
			)
			(layer "F.SilkS")
		)
		(fp_line
			(start -0.7874 0.4064)
			(end -0.7874 -0.4064)
			(stroke
				(width 0.1524)
				(type default)
			)
			(layer "F.SilkS")
		)
		(fp_line
			(start -0.7874 -0.4064)
			(end 0.7874 -0.4064)
			(stroke
				(width 0.1524)
				(type default)
			)
			(layer "F.SilkS")
		)
		(fp_line
			(start 0.67945 0.3048)
			(end 0.120396 0.3048)
			(stroke
				(width 0.1)
				(type default)
			)
			(layer "F.Fab")
		)
		(fp_line
			(start 0.67945 -0.3048)
			(end 0.67945 0.3048)
			(stroke
				(width 0.1)
				(type default)
			)
			(layer "F.Fab")
		)
		(fp_line
			(start 0.12065 -0.2794)
			(end 0.12065 -0.3048)
			(stroke
				(width 0.1)
				(type default)
			)
			(layer "F.Fab")
		)
		(fp_line
			(start 0.12065 -0.3048)
			(end 0.67945 -0.3048)
			(stroke
				(width 0.1)
				(type default)
			)
			(layer "F.Fab")
		)
		(fp_line
			(start 0.120396 0.3048)
			(end 0.120396 0.2794)
			(stroke
				(width 0.1)
				(type default)
			)
			(layer "F.Fab")
		)
		(fp_line
			(start 0.120396 0.2794)
			(end -0.12065 0.2794)
			(stroke
				(width 0.1)
				(type default)
			)
			(layer "F.Fab")
		)
		(fp_line
			(start -0.12065 0.3048)
			(end -0.67945 0.3048)
			(stroke
				(width 0.1)
				(type default)
			)
			(layer "F.Fab")
		)
		(fp_line
			(start -0.12065 0.2794)
			(end -0.12065 0.3048)
			(stroke
				(width 0.1)
				(type default)
			)
			(layer "F.Fab")
		)
		(fp_line
			(start -0.12065 -0.2794)
			(end 0.12065 -0.2794)
			(stroke
				(width 0.1)
				(type default)
			)
			(layer "F.Fab")
		)
		(fp_line
			(start -0.12065 -0.305054)
			(end -0.12065 -0.2794)
			(stroke
				(width 0.1)
				(type default)
			)
			(layer "F.Fab")
		)
		(fp_line
			(start -0.67945 0.3048)
			(end -0.67945 -0.305054)
			(stroke
				(width 0.1)
				(type default)
			)
			(layer "F.Fab")
		)
		(fp_line
			(start -0.67945 -0.305054)
			(end -0.12065 -0.305054)
			(stroke
				(width 0.1)
				(type default)
			)
			(layer "F.Fab")
		)
		(pad "1" smd circle
			(at -0.40005 0 180)
			(size 0 0)
			(layers "F.Cu" "F.Mask" "F.Paste")
			(net "P3V3_AUX")
		)
		(pad "2" smd circle
			(at 0.40005 0 180)
			(size 0 0)
			(layers "F.Cu" "F.Mask" "F.Paste")
			(net "PCA9548_PCIE0_ADDR2")
		)
	)
	(footprint ""
		(layer "F.Cu")
		(at 10.3124 -401.523708)
		(property "Reference" ""
			(at 0 0 0)
			(layer "F.SilkS")
			(hide yes)
			(effects
				(font
					(size 1.27 1.27)
				)
			)
		)
		(property "Value" ""
			(at 0 0 0)
			(layer "F.Fab")
			(effects
				(font
					(size 1.27 1.27)
				)
			)
		)
		(duplicate_pad_numbers_are_jumpers no)
		(pad "1" smd circle
			(at 0 0)
			(size 0.9906 0.9906)
			(layers "F.Cu" "F.Mask" "F.Paste")
			(net "Net_286")
		)
		(zone
			(layer "F.Cu")
			(hatch none 0.5)
			(connect_pads
				(clearance 0)
			)
			(min_thickness 0.25)
			(keepout
				(tracks not_allowed)
				(vias allowed)
				(pads allowed)
				(copperpour not_allowed)
				(footprints allowed)
			)
			(placement
				(enabled no)
				(sheetname "")
			)
			(fill
				(thermal_gap 0.5)
				(thermal_bridge_width 0.5)
				(island_removal_mode 0)
			)
			(polygon
				(pts
					(arc
						(start 11.938 -401.523708)
						(mid 8.6868 -401.523708)
						(end 11.938 -401.523708)
					)
				)
			)
		)
	)
)
